# Data Center RDIMM DDR4 Tester — assets/stackup.csv
Name;Type;Material;Thickness[mm];Constant
F.Mask;Top Solder Mask;;0.01;
F.Cu;copper;;0.035;
dielectric 1;prepreg;1080(69%)+106(74%)S1000-2MB;0.074;3.9
In1.Cu;copper;;0.035;
dielectric 2;prepreg;1080(69%)+106(74%)S1000-2MB;0.112;3.9
In2.Cu;copper;;0.035;
dielectric 3;prepreg;1080(69%)+106(74%)S1000-2MB;0.126;3.9
In3.Cu;copper;;0.035;
dielectric 4;prepreg;1080(69%)+106(74%)S1000-2MB;0.126;3.9
In4.Cu;copper;;0.035;
dielectric 5;core;S1000-2M;0.13;4.9
In5.Cu;copper;;0.035;
dielectric 6;prepreg;1080(69%)+106(74%)S1000-2MB;0.106;3.9
In6.Cu;copper;;0.035;
dielectric 7;prepreg;S1000-2M;0.2;4.9
In7.Cu;copper;;0.035;
dielectric 8;core;106(74%)+1080(69%)S1000-2MB;0.114;3.9
In8.Cu;copper;;0.035;
dielectric 9;prepreg;106(74%)+1080(69%)S1000-2MB;0.1263;3.9
In9.Cu;copper;;0.035;
dielectric 10;core;106(74%)+1080(69%)S1000-2MB;0.112;3.9
In10.Cu;copper;;0.035;
dielectric 11;prepreg;106(74%)+1080(69%)S1000-2MB;0.074;3.9
B.Cu;copper;;0.035;
B.Mask;Bottom Solder Mask;;0.01;
